(kicad_pcb
	(version 20260206)
	(generator "pcbnew")
	(generator_version "10.0")
	(general
		(thickness 1.6)
		(legacy_teardrops no)
	)
	(paper "A4")
	(title_block
		(title "Bryce Canyon_R.DPB_16317-1_OCP.brd")
		(comment 1 "Bryce Canyon / footprints 34-36 of 2099")
	)
	(layers
		(0 "F.Cu" signal "TOP")
		(4 "In1.Cu" signal "L2GND")
		(6 "In2.Cu" signal "L3")
		(8 "In3.Cu" signal "L4VCC")
		(10 "In4.Cu" signal "L5VCC")
		(12 "In5.Cu" signal "L6")
		(14 "In6.Cu" signal "L7GND")
		(2 "B.Cu" signal "BOTTOM")
		(9 "F.Adhes" user "F.Adhesive")
		(11 "B.Adhes" user "B.Adhesive")
		(13 "F.Paste" user "Package Geometry/Pastemask Top")
		(15 "B.Paste" user "Package Geometry/Pastemask Bottom")
		(5 "F.SilkS" user "Ref Des/Silkscreen Top")
		(7 "B.SilkS" user "Ref Des/Silkscreen Bottom")
		(1 "F.Mask" user "Board Geometry/Soldermask Top")
		(3 "B.Mask" user "Board Geometry/Soldermask Bottom")
		(17 "Dwgs.User" user "User.Drawings")
		(19 "Cmts.User" user "User.Comments")
		(21 "Eco1.User" user "User.Eco1")
		(23 "Eco2.User" user "User.Eco2")
		(25 "Edge.Cuts" user "Board Geometry/Outline")
		(27 "Margin" user)
		(31 "F.CrtYd" user "Package Geometry/Place Bound Top")
		(29 "B.CrtYd" user "Package Geometry/Place Bound Bottom")
		(35 "F.Fab" user "Ref Des/Assembly Top")
		(33 "B.Fab" user "Ref Des/Assembly Bottom")
	)
	(footprint ""
		(layer "F.Cu")
		(at 91.300046 -28.910026 -90)
		(property "Reference" "HDDSAS26"
			(at 0 0 270)
			(layer "F.SilkS")
			(hide yes)
			(effects
				(font
					(size 1.27 1.27)
				)
			)
		)
		(property "Value" "SKT-SAS15P-14P-45-GP"
			(at -20.7645 -8.9789 270)
			(unlocked yes)
			(layer "F.Fab")
			(hide yes)
			(effects
				(font
					(size 1.016 1.016)
					(thickness 0.1524)
				)
			)
		)
		(property "Device Type" "10120818-001C-TRLF"
			(at -20.7645 -10.5029 270)
			(unlocked yes)
			(layer "F.Fab")
			(hide yes)
			(effects
				(font
					(size 1.016 1.016)
					(thickness 0.1524)
				)
			)
		)
		(duplicate_pad_numbers_are_jumpers no)
		(fp_line
			(start 1.651 4.2926)
			(end 1.651 3.0099)
			(stroke
				(width 0.1524)
				(type default)
			)
			(layer "F.SilkS")
		)
		(fp_line
			(start 8.509 4.2926)
			(end 1.651 4.2926)
			(stroke
				(width 0.1524)
				(type default)
			)
			(layer "F.SilkS")
		)
		(fp_line
			(start -23.4188 3.0099)
			(end -23.4188 -3.2512)
			(stroke
				(width 0.1524)
				(type default)
			)
			(layer "F.SilkS")
		)
		(fp_line
			(start 1.651 3.0099)
			(end -23.4188 3.0099)
			(stroke
				(width 0.1524)
				(type default)
			)
			(layer "F.SilkS")
		)
		(fp_line
			(start 8.509 3.0099)
			(end 8.509 4.2926)
			(stroke
				(width 0.1524)
				(type default)
			)
			(layer "F.SilkS")
		)
		(fp_line
			(start 23.4188 3.0099)
			(end 8.509 3.0099)
			(stroke
				(width 0.1524)
				(type default)
			)
			(layer "F.SilkS")
		)
		(fp_line
			(start -23.4188 -3.2512)
			(end 23.4188 -3.2512)
			(stroke
				(width 0.1524)
				(type default)
			)
			(layer "F.SilkS")
		)
		(fp_line
			(start 23.4188 -3.2512)
			(end 23.4188 3.0099)
			(stroke
				(width 0.1524)
				(type default)
			)
			(layer "F.SilkS")
		)
		(fp_line
			(start 15.5067 -3.3401)
			(end 16.2687 -3.3401)
			(stroke
				(width 0.3302)
				(type default)
			)
			(layer "F.SilkS")
		)
		(fp_poly
			(pts
				(xy 15.868904 -3.230372) (xy 16.503904 -3.865372) (xy 15.233904 -3.865372)
			)
			(stroke
				(width 0)
				(type default)
			)
			(fill yes)
			(layer "F.SilkS")
		)
		(fp_poly
			(pts
				(xy -22.8727 -2.7559) (xy 22.8727 -2.7559) (xy 22.8727 2.7559) (xy 8.255 2.7559) (xy 8.255 3.5179)
				(xy 1.905 3.5179) (xy 1.905 2.7559) (xy -22.8727 2.7559)
			)
			(stroke
				(width 0)
				(type default)
			)
			(fill no)
			(layer "F.CrtYd")
		)
		(fp_poly
			(pts
				(xy 1.397 4.5466) (xy 1.397 3.2639) (xy -23.6728 3.2639) (xy -23.6728 -3.5052) (xy 23.6728 -3.5052)
				(xy 23.6728 -0.00635) (xy 22.8727 -0.00635) (xy 22.8727 -2.7559) (xy -22.8727 -2.7559) (xy -22.8727 2.7559)
				(xy 1.905 2.7559) (xy 1.905 3.5179) (xy 8.255 3.5179) (xy 8.255 2.7559) (xy 22.8727 2.7559) (xy 22.8727 0.00635)
				(xy 23.6728 0.00635) (xy 23.6728 3.2639) (xy 8.763 3.2639) (xy 8.763 4.5466)
			)
			(stroke
				(width 0)
				(type default)
			)
			(fill no)
			(layer "F.CrtYd")
		)
		(fp_poly
			(pts
				(xy 1.397 4.5466) (xy 1.397 3.2639) (xy -23.6728 3.2639) (xy -23.6728 -3.5052) (xy 23.6728 -3.5052)
				(xy 23.6728 3.2639) (xy 8.763 3.2639) (xy 8.763 4.5466)
			)
			(stroke
				(width 0)
				(type default)
			)
			(fill no)
			(layer "F.Fab")
		)
		(pad "" np_thru_hole circle
			(at -18.874994 0 270)
			(size 0.254 0.254)
			(drill 1.3462)
			(layers "*.Cu" "*.Mask")
			(clearance 0.9017)
			(thermal_gap 0.9017)
		)
		(pad "" np_thru_hole circle
			(at 18.874994 0 270)
			(size 0.254 0.254)
			(drill 0.9398)
			(layers "*.Cu" "*.Mask")
			(clearance 0.6985)
			(thermal_gap 0.6985)
		)
		(pad "G1" smd rect
			(at 21.874988 0 270)
			(size 2.5908 2.5908)
			(layers "F.Cu" "F.Mask" "F.Paste")
			(net "GND")
		)
		(pad "G2" smd rect
			(at -21.874988 0 270)
			(size 2.5908 2.5908)
			(layers "F.Cu" "F.Mask" "F.Paste")
			(net "GND")
		)
		(pad "P1" smd rect
			(at 1.905 -1.82499 270)
			(size 0.6096 2.3622)
			(layers "F.Cu" "F.Mask" "F.Paste")
			(net "Net_1669")
		)
		(pad "P2" smd rect
			(at 0.635 -1.82499 270)
			(size 0.6096 2.3622)
			(layers "F.Cu" "F.Mask" "F.Paste")
			(net "Net_1670")
		)
		(pad "P3" smd rect
			(at -0.635 -1.82499 270)
			(size 0.6096 2.3622)
			(layers "F.Cu" "F.Mask" "F.Paste")
			(net "Net_1671")
		)
		(pad "P4" smd rect
			(at -1.905 -1.82499 270)
			(size 0.6096 2.3622)
			(layers "F.Cu" "F.Mask" "F.Paste")
			(net "GND")
		)
		(pad "P5" smd rect
			(at -3.175 -1.82499 270)
			(size 0.6096 2.3622)
			(layers "F.Cu" "F.Mask" "F.Paste")
			(net "HDD_PRSNT_26")
		)
		(pad "P6" smd rect
			(at -4.445 -1.82499 270)
			(size 0.6096 2.3622)
			(layers "F.Cu" "F.Mask" "F.Paste")
			(net "GND")
		)
		(pad "P7" smd rect
			(at -5.715 -1.82499 270)
			(size 0.6096 2.3622)
			(layers "F.Cu" "F.Mask" "F.Paste")
			(net "5V_PRE_26")
		)
		(pad "P8" smd rect
			(at -6.985 -1.82499 270)
			(size 0.6096 2.3622)
			(layers "F.Cu" "F.Mask" "F.Paste")
			(net "P5V_HDD26")
		)
		(pad "P9" smd rect
			(at -8.255 -1.82499 270)
			(size 0.6096 2.3622)
			(layers "F.Cu" "F.Mask" "F.Paste")
			(net "P5V_HDD26")
		)
		(pad "P10" smd rect
			(at -9.525 -1.82499 270)
			(size 0.6096 2.3622)
			(layers "F.Cu" "F.Mask" "F.Paste")
			(net "GND")
		)
		(pad "P11" smd rect
			(at -10.795 -1.82499 270)
			(size 0.6096 2.3622)
			(layers "F.Cu" "F.Mask" "F.Paste")
			(net "ACT_HDD_26")
		)
		(pad "P12" smd rect
			(at -12.065 -1.82499 270)
			(size 0.6096 2.3622)
			(layers "F.Cu" "F.Mask" "F.Paste")
			(net "GND")
		)
		(pad "P13" smd rect
			(at -13.335 -1.82499 270)
			(size 0.6096 2.3622)
			(layers "F.Cu" "F.Mask" "F.Paste")
			(net "12V_PRE_26")
		)
		(pad "P14" smd rect
			(at -14.605 -1.82499 270)
			(size 0.6096 2.3622)
			(layers "F.Cu" "F.Mask" "F.Paste")
			(net "P12V_HDD26")
		)
		(pad "P15" smd rect
			(at -15.875 -1.82499 270)
			(size 0.6096 2.3622)
			(layers "F.Cu" "F.Mask" "F.Paste")
			(net "P12V_HDD26")
		)
		(pad "S1" smd rect
			(at 15.875 -1.82499 270)
			(size 0.6096 2.3622)
			(layers "F.Cu" "F.Mask" "F.Paste")
			(net "GND")
		)
		(pad "S2" smd rect
			(at 14.605 -1.82499 270)
			(size 0.6096 2.3622)
			(layers "F.Cu" "F.Mask" "F.Paste")
			(net "SAS_HDD_RX_P26")
		)
		(pad "S3" smd rect
			(at 13.335 -1.82499 270)
			(size 0.6096 2.3622)
			(layers "F.Cu" "F.Mask" "F.Paste")
			(net "SAS_HDD_RX_N26")
		)
		(pad "S4" smd rect
			(at 12.065 -1.82499 270)
			(size 0.6096 2.3622)
			(layers "F.Cu" "F.Mask" "F.Paste")
			(net "GND")
		)
		(pad "S5" smd rect
			(at 10.795 -1.82499 270)
			(size 0.6096 2.3622)
			(layers "F.Cu" "F.Mask" "F.Paste")
			(net "PHY_DRV_B_TO_SCC_B_26_DN")
		)
		(pad "S6" smd rect
			(at 9.525 -1.82499 270)
			(size 0.6096 2.3622)
			(layers "F.Cu" "F.Mask" "F.Paste")
			(net "PHY_DRV_B_TO_SCC_B_26_DP")
		)
		(pad "S7" smd rect
			(at 8.255 -1.82499 270)
			(size 0.6096 2.3622)
			(layers "F.Cu" "F.Mask" "F.Paste")
			(net "GND")
		)
		(pad "S8" smd rect
			(at 7.480046 2.845054 270)
			(size 0.508 2.3622)
			(layers "F.Cu" "F.Mask" "F.Paste")
			(net "GND")
		)
		(pad "S9" smd rect
			(at 6.679946 2.845054 270)
			(size 0.508 2.3622)
			(layers "F.Cu" "F.Mask" "F.Paste")
			(net "Net_450")
		)
		(pad "S10" smd rect
			(at 5.8801 2.845054 270)
			(size 0.508 2.3622)
			(layers "F.Cu" "F.Mask" "F.Paste")
			(net "Net_342")
		)
		(pad "S11" smd rect
			(at 5.08 2.845054 270)
			(size 0.508 2.3622)
			(layers "F.Cu" "F.Mask" "F.Paste")
			(net "GND")
		)
		(pad "S12" smd rect
			(at 4.2799 2.845054 270)
			(size 0.508 2.3622)
			(layers "F.Cu" "F.Mask" "F.Paste")
			(net "Net_378")
		)
		(pad "S13" smd rect
			(at 3.480054 2.845054 270)
			(size 0.508 2.3622)
			(layers "F.Cu" "F.Mask" "F.Paste")
			(net "Net_414")
		)
		(pad "S14" smd rect
			(at 2.679954 2.845054 270)
			(size 0.508 2.3622)
			(layers "F.Cu" "F.Mask" "F.Paste")
			(net "GND")
		)
		(zone
			(layer "F.Cu")
			(hatch none 0.5)
			(connect_pads
				(clearance 0)
			)
			(min_thickness 0.25)
			(keepout
				(tracks allowed)
				(vias not_allowed)
				(pads allowed)
				(copperpour not_allowed)
				(footprints allowed)
			)
			(placement
				(enabled no)
				(sheetname "")
			)
			(fill
				(thermal_gap 0.5)
				(thermal_bridge_width 0.5)
				(island_removal_mode 0)
			)
			(polygon
				(pts
					(xy 94.957646 -45.648626) (xy 87.883746 -45.648626) (xy 87.883746 -52.582826) (xy 88.988646 -52.582826)
					(xy 88.988646 -48.468026) (xy 93.611446 -48.468026) (xy 93.611446 -52.582826) (xy 94.957646 -52.582826)
				)
			)
		)
		(zone
			(layer "F.Cu")
			(hatch none 0.5)
			(connect_pads
				(clearance 0)
			)
			(min_thickness 0.25)
			(keepout
				(tracks not_allowed)
				(vias allowed)
				(pads allowed)
				(copperpour not_allowed)
				(footprints allowed)
			)
			(placement
				(enabled no)
				(sheetname "")
			)
			(fill
				(thermal_gap 0.5)
				(thermal_bridge_width 0.5)
				(island_removal_mode 0)
			)
			(polygon
				(pts
					(xy 94.957646 -45.648626) (xy 87.883746 -45.648626) (xy 87.883746 -52.582826) (xy 88.988646 -52.582826)
					(xy 88.988646 -48.468026) (xy 93.611446 -48.468026) (xy 93.611446 -52.582826) (xy 94.957646 -52.582826)
				)
			)
		)
		(zone
			(layer "F.Cu")
			(hatch none 0.5)
			(connect_pads
				(clearance 0)
			)
			(min_thickness 0.25)
			(keepout
				(tracks allowed)
				(vias not_allowed)
				(pads allowed)
				(copperpour not_allowed)
				(footprints allowed)
			)
			(placement
				(enabled no)
				(sheetname "")
			)
			(fill
				(thermal_gap 0.5)
				(thermal_bridge_width 0.5)
				(island_removal_mode 0)
			)
			(polygon
				(pts
					(xy 94.957646 -12.171426) (xy 87.883746 -12.171426) (xy 87.883746 -5.237226) (xy 88.988646 -5.237226)
					(xy 88.988646 -9.352026) (xy 93.611446 -9.352026) (xy 93.611446 -5.237226) (xy 94.957646 -5.237226)
				)
			)
		)
		(zone
			(layer "F.Cu")
			(hatch none 0.5)
			(connect_pads
				(clearance 0)
			)
			(min_thickness 0.25)
			(keepout
				(tracks not_allowed)
				(vias allowed)
				(pads allowed)
				(copperpour not_allowed)
				(footprints allowed)
			)
			(placement
				(enabled no)
				(sheetname "")
			)
			(fill
				(thermal_gap 0.5)
				(thermal_bridge_width 0.5)
				(island_removal_mode 0)
			)
			(polygon
				(pts
					(xy 94.957646 -12.171426) (xy 87.883746 -12.171426) (xy 87.883746 -5.237226) (xy 88.988646 -5.237226)
					(xy 88.988646 -9.352026) (xy 93.611446 -9.352026) (xy 93.611446 -5.237226) (xy 94.957646 -5.237226)
				)
			)
		)
		(zone
			(layers "F.Cu" "B.Cu" "In1.Cu" "In2.Cu" "In3.Cu" "In4.Cu" "In5.Cu" "In6.Cu")
			(hatch none 0.5)
			(connect_pads
				(clearance 0)
			)
			(min_thickness 0.25)
			(keepout
				(tracks not_allowed)
				(vias allowed)
				(pads allowed)
				(copperpour not_allowed)
				(footprints allowed)
			)
			(placement
				(enabled no)
				(sheetname "")
			)
			(fill
				(thermal_gap 0.5)
				(thermal_bridge_width 0.5)
				(island_removal_mode 0)
			)
			(polygon
				(pts
					(arc
						(start 92.074746 -10.035032)
						(mid 90.525346 -10.035032)
						(end 92.074746 -10.035032)
					)
				)
			)
		)
		(zone
			(layers "F.Cu" "B.Cu" "In1.Cu" "In2.Cu" "In3.Cu" "In4.Cu" "In5.Cu" "In6.Cu")
			(hatch none 0.5)
			(connect_pads
				(clearance 0)
			)
			(min_thickness 0.25)
			(keepout
				(tracks not_allowed)
				(vias allowed)
				(pads allowed)
				(copperpour not_allowed)
				(footprints allowed)
			)
			(placement
				(enabled no)
				(sheetname "")
			)
			(fill
				(thermal_gap 0.5)
				(thermal_bridge_width 0.5)
				(island_removal_mode 0)
			)
			(polygon
				(pts
					(arc
						(start 92.277946 -47.78502)
						(mid 90.322146 -47.78502)
						(end 92.277946 -47.78502)
					)
				)
			)
		)
	)
	(footprint ""
		(layer "F.Cu")
		(at 147.548092 -212.44687 -90)
		(property "Reference" "R213"
			(at 0 0 270)
			(layer "F.SilkS")
			(hide yes)
			(effects
				(font
					(size 1.27 1.27)
				)
			)
		)
		(property "Value" "4K7R2F-GP"
			(at 0.064008 -3.993896 270)
			(unlocked yes)
			(layer "F.Fab")
			(hide yes)
			(effects
				(font
					(size 1.016 1.016)
					(thickness 0.1524)
				)
			)
		)
		(property "Device Type" "R402H16"
			(at 0.064008 -5.517896 270)
			(unlocked yes)
			(layer "F.Fab")
			(hide yes)
			(effects
				(font
					(size 1.016 1.016)
					(thickness 0.1524)
				)
			)
		)
		(duplicate_pad_numbers_are_jumpers no)
		(fp_line
			(start -0.508 -0.9398)
			(end -0.508 0.9398)
			(stroke
				(width 0.1524)
				(type default)
			)
			(layer "F.SilkS")
		)
		(fp_line
			(start 0.508 -0.9398)
			(end -0.508 -0.9398)
			(stroke
				(width 0.1524)
				(type default)
			)
			(layer "F.SilkS")
		)
		(fp_rect
			(start -0.508 0.9398)
			(end 0.508 -0.9398)
			(stroke
				(width 0)
				(type default)
			)
			(fill no)
			(layer "F.CrtYd")
		)
		(fp_rect
			(start -0.508 0.9398)
			(end 0.508 -0.9398)
			(stroke
				(width 0)
				(type default)
			)
			(fill no)
			(layer "F.Fab")
		)
		(pad "1" smd custom
			(at 0 -0.4445 270)
			(size 0.1397 0.1397)
			(layers "F.Cu" "F.Mask" "F.Paste")
			(net "DRIVE_B_4_ACT")
			(options
				(clearance outline)
				(anchor circle)
			)
			(primitives
				(gr_poly
					(pts
						(arc
							(start -0.1778 -0.2794)
							(mid -0.249642 -0.249642)
							(end -0.2794 -0.1778)
						)
						(arc
							(start -0.2794 0.1778)
							(mid -0.249642 0.249642)
							(end -0.1778 0.2794)
						)
						(arc
							(start 0.1778 0.2794)
							(mid 0.249642 0.249642)
							(end 0.2794 0.1778)
						)
						(arc
							(start 0.2794 -0.1778)
							(mid 0.249642 -0.249642)
							(end 0.1778 -0.2794)
						)
					)
					(width 0)
					(fill yes)
				)
			)
		)
		(pad "2" smd custom
			(at 0 0.4445 270)
			(size 0.1397 0.1397)
			(layers "F.Cu" "F.Mask" "F.Paste")
			(net "GND")
			(options
				(clearance outline)
				(anchor circle)
			)
			(primitives
				(gr_poly
					(pts
						(arc
							(start -0.1778 -0.2794)
							(mid -0.249642 -0.249642)
							(end -0.2794 -0.1778)
						)
						(arc
							(start -0.2794 0.1778)
							(mid -0.249642 0.249642)
							(end -0.1778 0.2794)
						)
						(arc
							(start 0.1778 0.2794)
							(mid 0.249642 0.249642)
							(end 0.2794 0.1778)
						)
						(arc
							(start 0.2794 -0.1778)
							(mid 0.249642 -0.249642)
							(end 0.1778 -0.2794)
						)
					)
					(width 0)
					(fill yes)
				)
			)
		)
	)
	(footprint ""
		(layer "F.Cu")
		(at 83.3374 -148.717 -90)
		(property "Reference" "C212"
			(at 0 0 270)
			(layer "F.SilkS")
			(hide yes)
			(effects
				(font
					(size 1.27 1.27)
				)
			)
		)
		(property "Value" "SC1U16V3KX-5GP"
			(at 0 -2.8194 270)
			(unlocked yes)
			(layer "F.Fab")
			(hide yes)
			(effects
				(font
					(size 1.016 1.016)
					(thickness 0.1524)
				)
			)
		)
		(property "Device Type" "C603H36"
			(at 0 -4.3434 270)
			(unlocked yes)
			(layer "F.Fab")
			(hide yes)
			(effects
				(font
					(size 1.016 1.016)
					(thickness 0.1524)
				)
			)
		)
		(duplicate_pad_numbers_are_jumpers no)
		(fp_line
			(start 0.508 0)
			(end -0.508 0)
			(stroke
				(width 0.2032)
				(type default)
			)
			(layer "F.SilkS")
		)
		(fp_rect
			(start -0.5842 1.3335)
			(end 0.5842 -1.3335)
			(stroke
				(width 0)
				(type default)
			)
			(fill no)
			(layer "F.CrtYd")
		)
		(fp_rect
			(start -0.5842 1.3335)
			(end 0.5842 -1.3335)
			(stroke
				(width 0)
				(type default)
			)
			(fill no)
			(layer "F.Fab")
		)
		(pad "1" smd custom
			(at 0 -0.762 270)
			(size 0.2159 0.2159)
			(layers "F.Cu" "F.Mask" "F.Paste")
			(net "P5V_HDD14")
			(options
				(clearance outline)
				(anchor circle)
			)
			(primitives
				(gr_poly
					(pts
						(arc
							(start -0.3302 -0.4318)
							(mid -0.402042 -0.402042)
							(end -0.4318 -0.3302)
						)
						(arc
							(start -0.4318 0.3302)
							(mid -0.402042 0.402042)
							(end -0.3302 0.4318)
						)
						(arc
							(start 0.3302 0.4318)
							(mid 0.402042 0.402042)
							(end 0.4318 0.3302)
						)
						(arc
							(start 0.4318 -0.3302)
							(mid 0.402042 -0.402042)
							(end 0.3302 -0.4318)
						)
					)
					(width 0)
					(fill yes)
				)
			)
		)
		(pad "2" smd custom
			(at 0 0.762 270)
			(size 0.2159 0.2159)
			(layers "F.Cu" "F.Mask" "F.Paste")
			(net "GND")
			(options
				(clearance outline)
				(anchor circle)
			)
			(primitives
				(gr_poly
					(pts
						(arc
							(start -0.3302 -0.4318)
							(mid -0.402042 -0.402042)
							(end -0.4318 -0.3302)
						)
						(arc
							(start -0.4318 0.3302)
							(mid -0.402042 0.402042)
							(end -0.3302 0.4318)
						)
						(arc
							(start 0.3302 0.4318)
							(mid 0.402042 0.402042)
							(end 0.4318 0.3302)
						)
						(arc
							(start 0.4318 -0.3302)
							(mid 0.402042 -0.402042)
							(end 0.3302 -0.4318)
						)
					)
					(width 0)
					(fill yes)
				)
			)
		)
	)
)
